(kicad_pcb
	(version 20260206)
	(generator "pcbnew")
	(generator_version "10.0")
	(general
		(thickness 1.6)
		(legacy_teardrops no)
	)
	(paper "A4")
	(title_block
		(title "04192023_DAF0TMB3IC0_F0TG_MB_C_brd_V02_OCP.brd")
		(comment 1 "Grand Teton / footprints 4524-4531 of 8354")
	)
	(layers
		(0 "F.Cu" signal "TOP")
		(4 "In1.Cu" signal "GND")
		(6 "In2.Cu" signal "IN1")
		(8 "In3.Cu" signal "GND1")
		(10 "In4.Cu" signal "IN2")
		(12 "In5.Cu" signal "GND2")
		(14 "In6.Cu" signal "IN3")
		(16 "In7.Cu" signal "GND3")
		(18 "In8.Cu" signal "VCC")
		(20 "In9.Cu" signal "VCC1")
		(22 "In10.Cu" signal "GND4")
		(24 "In11.Cu" signal "IN4")
		(26 "In12.Cu" signal "GND5")
		(28 "In13.Cu" signal "IN5")
		(30 "In14.Cu" signal "GND6")
		(32 "In15.Cu" signal "IN6")
		(34 "In16.Cu" signal "GND7")
		(2 "B.Cu" signal "BOTTOM")
		(9 "F.Adhes" user "F.Adhesive")
		(11 "B.Adhes" user "B.Adhesive")
		(13 "F.Paste" user "Package Geometry/Pastemask Top")
		(15 "B.Paste" user "Package Geometry/Pastemask Bottom")
		(5 "F.SilkS" user "Ref Des/Silkscreen Top")
		(7 "B.SilkS" user "Ref Des/Silkscreen Bottom")
		(1 "F.Mask" user "Board Geometry/Soldermask Top")
		(3 "B.Mask" user "Board Geometry/Soldermask Bottom")
		(17 "Dwgs.User" user "User.Drawings")
		(19 "Cmts.User" user "User.Comments")
		(21 "Eco1.User" user "User.Eco1")
		(23 "Eco2.User" user "User.Eco2")
		(25 "Edge.Cuts" user "Board Geometry/Outline")
		(27 "Margin" user)
		(31 "F.CrtYd" user "Package Geometry/Place Bound Top")
		(29 "B.CrtYd" user "Package Geometry/Place Bound Bottom")
		(35 "F.Fab" user "Ref Des/Assembly Top")
		(33 "B.Fab" user "Ref Des/Assembly Bottom")
	)
	(footprint ""
		(layer "F.Cu")
		(at 146.194018 -76.877672 90)
		(property "Reference" "PR8003"
			(at 0 0 90)
			(layer "F.SilkS")
			(hide yes)
			(effects
				(font
					(size 1.27 1.27)
				)
			)
		)
		(property "Value" ""
			(at 0 0 90)
			(layer "F.Fab")
			(effects
				(font
					(size 1.27 1.27)
				)
			)
		)
		(duplicate_pad_numbers_are_jumpers no)
		(fp_line
			(start 0.7874 -0.4064)
			(end 0.7874 0.4064)
			(stroke
				(width 0.1524)
				(type default)
			)
			(layer "F.SilkS")
		)
		(fp_line
			(start -0.7874 -0.4064)
			(end 0.7874 -0.4064)
			(stroke
				(width 0.1524)
				(type default)
			)
			(layer "F.SilkS")
		)
		(fp_line
			(start 0.7874 0.4064)
			(end -0.7874 0.4064)
			(stroke
				(width 0.1524)
				(type default)
			)
			(layer "F.SilkS")
		)
		(fp_line
			(start -0.7874 0.4064)
			(end -0.7874 -0.4064)
			(stroke
				(width 0.1524)
				(type default)
			)
			(layer "F.SilkS")
		)
		(fp_line
			(start -0.12065 -0.305054)
			(end -0.12065 -0.2794)
			(stroke
				(width 0.1)
				(type default)
			)
			(layer "F.Fab")
		)
		(fp_line
			(start -0.67945 -0.305054)
			(end -0.12065 -0.305054)
			(stroke
				(width 0.1)
				(type default)
			)
			(layer "F.Fab")
		)
		(fp_line
			(start 0.67945 -0.3048)
			(end 0.67945 0.3048)
			(stroke
				(width 0.1)
				(type default)
			)
			(layer "F.Fab")
		)
		(fp_line
			(start 0.12065 -0.3048)
			(end 0.67945 -0.3048)
			(stroke
				(width 0.1)
				(type default)
			)
			(layer "F.Fab")
		)
		(fp_line
			(start 0.12065 -0.2794)
			(end 0.12065 -0.3048)
			(stroke
				(width 0.1)
				(type default)
			)
			(layer "F.Fab")
		)
		(fp_line
			(start -0.12065 -0.2794)
			(end 0.12065 -0.2794)
			(stroke
				(width 0.1)
				(type default)
			)
			(layer "F.Fab")
		)
		(fp_line
			(start 0.120396 0.2794)
			(end -0.12065 0.2794)
			(stroke
				(width 0.1)
				(type default)
			)
			(layer "F.Fab")
		)
		(fp_line
			(start -0.12065 0.2794)
			(end -0.12065 0.3048)
			(stroke
				(width 0.1)
				(type default)
			)
			(layer "F.Fab")
		)
		(fp_line
			(start 0.67945 0.3048)
			(end 0.120396 0.3048)
			(stroke
				(width 0.1)
				(type default)
			)
			(layer "F.Fab")
		)
		(fp_line
			(start 0.120396 0.3048)
			(end 0.120396 0.2794)
			(stroke
				(width 0.1)
				(type default)
			)
			(layer "F.Fab")
		)
		(fp_line
			(start -0.12065 0.3048)
			(end -0.67945 0.3048)
			(stroke
				(width 0.1)
				(type default)
			)
			(layer "F.Fab")
		)
		(fp_line
			(start -0.67945 0.3048)
			(end -0.67945 -0.305054)
			(stroke
				(width 0.1)
				(type default)
			)
			(layer "F.Fab")
		)
		(pad "1" smd circle
			(at -0.40005 0 90)
			(size 0 0)
			(layers "F.Cu" "F.Mask" "F.Paste")
			(net "SW_P1V8_AUX_BT")
		)
		(pad "2" smd circle
			(at 0.40005 0 90)
			(size 0 0)
			(layers "F.Cu" "F.Mask" "F.Paste")
			(net "SW_P1V8_AUX_BT_R")
		)
	)
	(footprint ""
		(layer "F.Cu")
		(at 116.36121 -61.602112 90)
		(property "Reference" "C1554"
			(at 0 0 90)
			(layer "F.SilkS")
			(hide yes)
			(effects
				(font
					(size 1.27 1.27)
				)
			)
		)
		(property "Value" ""
			(at 0 0 90)
			(layer "F.Fab")
			(effects
				(font
					(size 1.27 1.27)
				)
			)
		)
		(duplicate_pad_numbers_are_jumpers no)
		(fp_line
			(start 0.7874 -0.4064)
			(end 0.7874 0.4064)
			(stroke
				(width 0.1524)
				(type default)
			)
			(layer "F.SilkS")
		)
		(fp_line
			(start -0.7874 -0.4064)
			(end 0.7874 -0.4064)
			(stroke
				(width 0.1524)
				(type default)
			)
			(layer "F.SilkS")
		)
		(fp_line
			(start 0.7874 0.4064)
			(end -0.7874 0.4064)
			(stroke
				(width 0.1524)
				(type default)
			)
			(layer "F.SilkS")
		)
		(fp_line
			(start -0.7874 0.4064)
			(end -0.7874 -0.4064)
			(stroke
				(width 0.1524)
				(type default)
			)
			(layer "F.SilkS")
		)
		(fp_line
			(start -0.12065 -0.305054)
			(end -0.12065 -0.2794)
			(stroke
				(width 0.1)
				(type default)
			)
			(layer "F.Fab")
		)
		(fp_line
			(start -0.67945 -0.305054)
			(end -0.12065 -0.305054)
			(stroke
				(width 0.1)
				(type default)
			)
			(layer "F.Fab")
		)
		(fp_line
			(start 0.67945 -0.3048)
			(end 0.67945 0.3048)
			(stroke
				(width 0.1)
				(type default)
			)
			(layer "F.Fab")
		)
		(fp_line
			(start 0.12065 -0.3048)
			(end 0.67945 -0.3048)
			(stroke
				(width 0.1)
				(type default)
			)
			(layer "F.Fab")
		)
		(fp_line
			(start 0.12065 -0.2794)
			(end 0.12065 -0.3048)
			(stroke
				(width 0.1)
				(type default)
			)
			(layer "F.Fab")
		)
		(fp_line
			(start -0.12065 -0.2794)
			(end 0.12065 -0.2794)
			(stroke
				(width 0.1)
				(type default)
			)
			(layer "F.Fab")
		)
		(fp_line
			(start 0.120396 0.2794)
			(end -0.12065 0.2794)
			(stroke
				(width 0.1)
				(type default)
			)
			(layer "F.Fab")
		)
		(fp_line
			(start -0.12065 0.2794)
			(end -0.12065 0.3048)
			(stroke
				(width 0.1)
				(type default)
			)
			(layer "F.Fab")
		)
		(fp_line
			(start 0.67945 0.3048)
			(end 0.120396 0.3048)
			(stroke
				(width 0.1)
				(type default)
			)
			(layer "F.Fab")
		)
		(fp_line
			(start 0.120396 0.3048)
			(end 0.120396 0.2794)
			(stroke
				(width 0.1)
				(type default)
			)
			(layer "F.Fab")
		)
		(fp_line
			(start -0.12065 0.3048)
			(end -0.67945 0.3048)
			(stroke
				(width 0.1)
				(type default)
			)
			(layer "F.Fab")
		)
		(fp_line
			(start -0.67945 0.3048)
			(end -0.67945 -0.305054)
			(stroke
				(width 0.1)
				(type default)
			)
			(layer "F.Fab")
		)
		(pad "1" smd circle
			(at -0.40005 0 90)
			(size 0 0)
			(layers "F.Cu" "F.Mask" "F.Paste")
			(net "P3V3_AUX")
		)
		(pad "2" smd circle
			(at 0.40005 0 90)
			(size 0 0)
			(layers "F.Cu" "F.Mask" "F.Paste")
			(net "GND")
		)
	)
	(footprint ""
		(layer "F.Cu")
		(at 78.028546 -394.166852 -90)
		(property "Reference" "R794"
			(at 0 0 270)
			(layer "F.SilkS")
			(hide yes)
			(effects
				(font
					(size 1.27 1.27)
				)
			)
		)
		(property "Value" ""
			(at 0 0 270)
			(layer "F.Fab")
			(effects
				(font
					(size 1.27 1.27)
				)
			)
		)
		(duplicate_pad_numbers_are_jumpers no)
		(fp_line
			(start -0.32512 0.175006)
			(end -0.32512 -0.175006)
			(stroke
				(width 0.1)
				(type default)
			)
			(layer "F.Fab")
		)
		(fp_line
			(start 0.32512 0.175006)
			(end -0.32512 0.175006)
			(stroke
				(width 0.1)
				(type default)
			)
			(layer "F.Fab")
		)
		(fp_line
			(start -0.32512 -0.175006)
			(end 0.32512 -0.175006)
			(stroke
				(width 0.1)
				(type default)
			)
			(layer "F.Fab")
		)
		(fp_line
			(start 0.32512 -0.175006)
			(end 0.32512 0.175006)
			(stroke
				(width 0.1)
				(type default)
			)
			(layer "F.Fab")
		)
		(pad "1" smd rect
			(at -0.2667 0 270)
			(size 0.3048 0.381)
			(layers "F.Cu" "F.Mask" "F.Paste")
			(net "MODE_RT_CPU1_P1")
		)
		(pad "2" smd rect
			(at 0.2667 0 90)
			(size 0.3048 0.381)
			(layers "F.Cu" "F.Mask" "F.Paste")
			(net "GND")
		)
	)
	(footprint ""
		(layer "F.Cu")
		(at 43.904154 -373.03583 -90)
		(property "Reference" "C832"
			(at 0 0 270)
			(layer "F.SilkS")
			(hide yes)
			(effects
				(font
					(size 1.27 1.27)
				)
			)
		)
		(property "Value" ""
			(at 0 0 270)
			(layer "F.Fab")
			(effects
				(font
					(size 1.27 1.27)
				)
			)
		)
		(duplicate_pad_numbers_are_jumpers no)
		(fp_line
			(start -0.299974 0.150114)
			(end -0.299974 -0.150114)
			(stroke
				(width 0.1)
				(type default)
			)
			(layer "F.Fab")
		)
		(fp_line
			(start 0.299974 0.150114)
			(end -0.299974 0.150114)
			(stroke
				(width 0.1)
				(type default)
			)
			(layer "F.Fab")
		)
		(fp_line
			(start -0.299974 -0.150114)
			(end 0.299974 -0.150114)
			(stroke
				(width 0.1)
				(type default)
			)
			(layer "F.Fab")
		)
		(fp_line
			(start 0.299974 -0.150114)
			(end 0.299974 0.150114)
			(stroke
				(width 0.1)
				(type default)
			)
			(layer "F.Fab")
		)
		(pad "1" smd rect
			(at -0.2667 0 270)
			(size 0.3048 0.381)
			(layers "F.Cu" "F.Mask" "F.Paste")
			(net "P5E_CPU1_P0_TX_C_DN<2>")
		)
		(pad "2" smd rect
			(at 0.2667 0 270)
			(size 0.3048 0.381)
			(layers "F.Cu" "F.Mask" "F.Paste")
			(net "P5E_CPU1_P0_TX_DN<2>")
		)
	)
	(footprint ""
		(layer "F.Cu")
		(at 250.30303 -45.995082 -90)
		(property "Reference" "PR3960"
			(at 0 0 270)
			(layer "F.SilkS")
			(hide yes)
			(effects
				(font
					(size 1.27 1.27)
				)
			)
		)
		(property "Value" ""
			(at 0 0 270)
			(layer "F.Fab")
			(effects
				(font
					(size 1.27 1.27)
				)
			)
		)
		(duplicate_pad_numbers_are_jumpers no)
		(fp_line
			(start -0.7874 0.4064)
			(end -0.7874 -0.4064)
			(stroke
				(width 0.1524)
				(type default)
			)
			(layer "F.SilkS")
		)
		(fp_line
			(start 0.7874 0.4064)
			(end -0.7874 0.4064)
			(stroke
				(width 0.1524)
				(type default)
			)
			(layer "F.SilkS")
		)
		(fp_line
			(start -0.7874 -0.4064)
			(end 0.7874 -0.4064)
			(stroke
				(width 0.1524)
				(type default)
			)
			(layer "F.SilkS")
		)
		(fp_line
			(start 0.7874 -0.4064)
			(end 0.7874 0.4064)
			(stroke
				(width 0.1524)
				(type default)
			)
			(layer "F.SilkS")
		)
		(fp_line
			(start -0.67945 0.3048)
			(end -0.67945 -0.305054)
			(stroke
				(width 0.1)
				(type default)
			)
			(layer "F.Fab")
		)
		(fp_line
			(start -0.12065 0.3048)
			(end -0.67945 0.3048)
			(stroke
				(width 0.1)
				(type default)
			)
			(layer "F.Fab")
		)
		(fp_line
			(start 0.120396 0.3048)
			(end 0.120396 0.2794)
			(stroke
				(width 0.1)
				(type default)
			)
			(layer "F.Fab")
		)
		(fp_line
			(start 0.67945 0.3048)
			(end 0.120396 0.3048)
			(stroke
				(width 0.1)
				(type default)
			)
			(layer "F.Fab")
		)
		(fp_line
			(start -0.12065 0.2794)
			(end -0.12065 0.3048)
			(stroke
				(width 0.1)
				(type default)
			)
			(layer "F.Fab")
		)
		(fp_line
			(start 0.120396 0.2794)
			(end -0.12065 0.2794)
			(stroke
				(width 0.1)
				(type default)
			)
			(layer "F.Fab")
		)
		(fp_line
			(start -0.12065 -0.2794)
			(end 0.12065 -0.2794)
			(stroke
				(width 0.1)
				(type default)
			)
			(layer "F.Fab")
		)
		(fp_line
			(start 0.12065 -0.2794)
			(end 0.12065 -0.3048)
			(stroke
				(width 0.1)
				(type default)
			)
			(layer "F.Fab")
		)
		(fp_line
			(start 0.12065 -0.3048)
			(end 0.67945 -0.3048)
			(stroke
				(width 0.1)
				(type default)
			)
			(layer "F.Fab")
		)
		(fp_line
			(start 0.67945 -0.3048)
			(end 0.67945 0.3048)
			(stroke
				(width 0.1)
				(type default)
			)
			(layer "F.Fab")
		)
		(fp_line
			(start -0.67945 -0.305054)
			(end -0.12065 -0.305054)
			(stroke
				(width 0.1)
				(type default)
			)
			(layer "F.Fab")
		)
		(fp_line
			(start -0.12065 -0.305054)
			(end -0.12065 -0.2794)
			(stroke
				(width 0.1)
				(type default)
			)
			(layer "F.Fab")
		)
		(pad "1" smd circle
			(at -0.40005 0 270)
			(size 0 0)
			(layers "F.Cu" "F.Mask" "F.Paste")
			(net "P12V_AUX")
		)
		(pad "2" smd circle
			(at 0.40005 0 270)
			(size 0 0)
			(layers "F.Cu" "F.Mask" "F.Paste")
			(net "P12V_E1S_UV_0")
		)
	)
	(footprint ""
		(layer "F.Cu")
		(at 317.246 -362.839 90)
		(property "Reference" "PR600"
			(at 0 0 90)
			(layer "F.SilkS")
			(hide yes)
			(effects
				(font
					(size 1.27 1.27)
				)
			)
		)
		(property "Value" ""
			(at 0 0 90)
			(layer "F.Fab")
			(effects
				(font
					(size 1.27 1.27)
				)
			)
		)
		(duplicate_pad_numbers_are_jumpers no)
		(fp_line
			(start 0.7874 -0.4064)
			(end 0.7874 0.4064)
			(stroke
				(width 0.1524)
				(type default)
			)
			(layer "F.SilkS")
		)
		(fp_line
			(start -0.7874 -0.4064)
			(end 0.7874 -0.4064)
			(stroke
				(width 0.1524)
				(type default)
			)
			(layer "F.SilkS")
		)
		(fp_line
			(start 0.7874 0.4064)
			(end -0.7874 0.4064)
			(stroke
				(width 0.1524)
				(type default)
			)
			(layer "F.SilkS")
		)
		(fp_line
			(start -0.7874 0.4064)
			(end -0.7874 -0.4064)
			(stroke
				(width 0.1524)
				(type default)
			)
			(layer "F.SilkS")
		)
		(fp_line
			(start -0.12065 -0.305054)
			(end -0.12065 -0.2794)
			(stroke
				(width 0.1)
				(type default)
			)
			(layer "F.Fab")
		)
		(fp_line
			(start -0.67945 -0.305054)
			(end -0.12065 -0.305054)
			(stroke
				(width 0.1)
				(type default)
			)
			(layer "F.Fab")
		)
		(fp_line
			(start 0.67945 -0.3048)
			(end 0.67945 0.3048)
			(stroke
				(width 0.1)
				(type default)
			)
			(layer "F.Fab")
		)
		(fp_line
			(start 0.12065 -0.3048)
			(end 0.67945 -0.3048)
			(stroke
				(width 0.1)
				(type default)
			)
			(layer "F.Fab")
		)
		(fp_line
			(start 0.12065 -0.2794)
			(end 0.12065 -0.3048)
			(stroke
				(width 0.1)
				(type default)
			)
			(layer "F.Fab")
		)
		(fp_line
			(start -0.12065 -0.2794)
			(end 0.12065 -0.2794)
			(stroke
				(width 0.1)
				(type default)
			)
			(layer "F.Fab")
		)
		(fp_line
			(start 0.120396 0.2794)
			(end -0.12065 0.2794)
			(stroke
				(width 0.1)
				(type default)
			)
			(layer "F.Fab")
		)
		(fp_line
			(start -0.12065 0.2794)
			(end -0.12065 0.3048)
			(stroke
				(width 0.1)
				(type default)
			)
			(layer "F.Fab")
		)
		(fp_line
			(start 0.67945 0.3048)
			(end 0.120396 0.3048)
			(stroke
				(width 0.1)
				(type default)
			)
			(layer "F.Fab")
		)
		(fp_line
			(start 0.120396 0.3048)
			(end 0.120396 0.2794)
			(stroke
				(width 0.1)
				(type default)
			)
			(layer "F.Fab")
		)
		(fp_line
			(start -0.12065 0.3048)
			(end -0.67945 0.3048)
			(stroke
				(width 0.1)
				(type default)
			)
			(layer "F.Fab")
		)
		(fp_line
			(start -0.67945 0.3048)
			(end -0.67945 -0.305054)
			(stroke
				(width 0.1)
				(type default)
			)
			(layer "F.Fab")
		)
		(pad "1" smd circle
			(at -0.40005 0 90)
			(size 0 0)
			(layers "F.Cu" "F.Mask" "F.Paste")
			(net "PVDDCR_CPU1_P0_VINSEN")
		)
		(pad "2" smd circle
			(at 0.40005 0 90)
			(size 0 0)
			(layers "F.Cu" "F.Mask" "F.Paste")
			(net "GND")
		)
	)
	(footprint ""
		(layer "F.Cu")
		(at 94.631764 -408.517344 -90)
		(property "Reference" "C6659"
			(at 0 0 270)
			(layer "F.SilkS")
			(hide yes)
			(effects
				(font
					(size 1.27 1.27)
				)
			)
		)
		(property "Value" ""
			(at 0 0 270)
			(layer "F.Fab")
			(effects
				(font
					(size 1.27 1.27)
				)
			)
		)
		(duplicate_pad_numbers_are_jumpers no)
		(fp_line
			(start -0.299974 0.150114)
			(end -0.299974 -0.150114)
			(stroke
				(width 0.1)
				(type default)
			)
			(layer "F.Fab")
		)
		(fp_line
			(start 0.299974 0.150114)
			(end -0.299974 0.150114)
			(stroke
				(width 0.1)
				(type default)
			)
			(layer "F.Fab")
		)
		(fp_line
			(start -0.299974 -0.150114)
			(end 0.299974 -0.150114)
			(stroke
				(width 0.1)
				(type default)
			)
			(layer "F.Fab")
		)
		(fp_line
			(start 0.299974 -0.150114)
			(end 0.299974 0.150114)
			(stroke
				(width 0.1)
				(type default)
			)
			(layer "F.Fab")
		)
		(pad "1" smd rect
			(at -0.2667 0 270)
			(size 0.3048 0.381)
			(layers "F.Cu" "F.Mask" "F.Paste")
			(net "P5E_CPU1_P0_TX_BUF_C_DP<15>")
		)
		(pad "2" smd rect
			(at 0.2667 0 270)
			(size 0.3048 0.381)
			(layers "F.Cu" "F.Mask" "F.Paste")
			(net "P5E_CPU1_P0_TX_BUF_DP<15>")
		)
	)
	(footprint ""
		(layer "F.Cu")
		(at 116.10086 -181.240684 180)
		(property "Reference" "PL35"
			(at -0.781304 6.250178 0)
			(unlocked yes)
			(layer "F.SilkS")
			(effects
				(font
					(size 0.7874 0.5842)
					(thickness 0.1524)
				)
				(justify left)
			)
		)
		(property "Value" ""
			(at 0 0 180)
			(layer "F.Fab")
			(effects
				(font
					(size 1.27 1.27)
				)
			)
		)
		(duplicate_pad_numbers_are_jumpers no)
		(fp_line
			(start 3.750056 5.500116)
			(end 3.750056 -5.500116)
			(stroke
				(width 0.1524)
				(type default)
			)
			(layer "F.SilkS")
		)
		(fp_line
			(start 3.750056 -5.500116)
			(end 2.393442 -5.500116)
			(stroke
				(width 0.1524)
				(type default)
			)
			(layer "F.SilkS")
		)
		(fp_line
			(start 2.393442 5.500116)
			(end 3.750056 5.500116)
			(stroke
				(width 0.1524)
				(type default)
			)
			(layer "F.SilkS")
		)
		(fp_line
			(start -2.393442 5.500116)
			(end -3.750056 5.500116)
			(stroke
				(width 0.1524)
				(type default)
			)
			(layer "F.SilkS")
		)
		(fp_line
			(start -3.750056 5.500116)
			(end -3.750056 -5.500116)
			(stroke
				(width 0.1524)
				(type default)
			)
			(layer "F.SilkS")
		)
		(fp_line
			(start -3.750056 -5.500116)
			(end -2.393442 -5.500116)
			(stroke
				(width 0.1524)
				(type default)
			)
			(layer "F.SilkS")
		)
		(fp_poly
			(pts
				(xy -3.9116 -4.249928) (xy -4.3434 -4.034028) (xy -4.3434 -4.465828)
			)
			(stroke
				(width 0)
				(type default)
			)
			(fill yes)
			(layer "F.SilkS")
		)
		(fp_line
			(start 3.750056 5.500116)
			(end 3.750056 -5.500116)
			(stroke
				(width 0.1)
				(type default)
			)
			(layer "F.Fab")
		)
		(fp_line
			(start 3.750056 -5.500116)
			(end -3.750056 -5.500116)
			(stroke
				(width 0.1)
				(type default)
			)
			(layer "F.Fab")
		)
		(fp_line
			(start -3.750056 5.500116)
			(end 3.750056 5.500116)
			(stroke
				(width 0.1)
				(type default)
			)
			(layer "F.Fab")
		)
		(fp_line
			(start -3.750056 -5.500116)
			(end -3.750056 5.500116)
			(stroke
				(width 0.1)
				(type default)
			)
			(layer "F.Fab")
		)
		(fp_poly
			(pts
				(xy -4.9276 -4.757928) (xy -4.9276 -3.741928) (xy -3.9116 -4.249928)
			)
			(stroke
				(width 0)
				(type default)
			)
			(fill yes)
			(layer "F.Fab")
		)
		(pad "1" smd rect
			(at 0 -4.249928 90)
			(size 2.413 4.5212)
			(layers "F.Cu" "F.Mask" "F.Paste")
			(net "SW_PVDDCR_SOC_P1_SW1")
		)
		(pad "2" smd rect
			(at 0 -1.175004 90)
			(size 1.3716 4.5212)
			(layers "F.Cu" "F.Mask" "F.Paste")
			(net "IND_SOC_P1_CPL2")
		)
		(pad "3" smd rect
			(at 0 1.175004 90)
			(size 1.3716 4.5212)
			(layers "F.Cu" "F.Mask" "F.Paste")
			(net "GND")
		)
		(pad "4" smd rect
			(at 0 4.249928 90)
			(size 2.413 4.5212)
			(layers "F.Cu" "F.Mask" "F.Paste")
			(net "PVDDCR_SOC_P1")
		)
	)
)
